(kicad_pcb
	(version 20221018)
	(generator pcbnew)
	(general
    (thickness 1.518)
  )
	(paper "A4")
	(title_block
    (title "Kria K26 Devboard")
    (date "2024-03-26")
    (rev "1.2.5")
    (comment 1 "www.antmicro.com")
    (comment 2 "Antmicro Ltd.")
		(comment 9 "footprints 395-404 of 660")
	)
	(layers
    (0 "F.Cu" mixed)
    (1 "In1.Cu" power)
    (2 "In2.Cu" mixed)
    (3 "In3.Cu" power)
    (4 "In4.Cu" mixed)
    (5 "In5.Cu" power)
    (6 "In6.Cu" mixed)
    (31 "B.Cu" power)
    (32 "B.Adhes" user "B.Adhesive")
    (33 "F.Adhes" user "F.Adhesive")
    (34 "B.Paste" user)
    (35 "F.Paste" user)
    (36 "B.SilkS" user "B.Silkscreen")
    (37 "F.SilkS" user "F.Silkscreen")
    (38 "B.Mask" user)
    (39 "F.Mask" user)
    (40 "Dwgs.User" user "User.Drawings")
    (41 "Cmts.User" user "User.Comments")
    (42 "Eco1.User" user "User.Eco1")
    (43 "Eco2.User" user "User.Eco2")
    (44 "Edge.Cuts" user)
    (45 "Margin" user)
    (46 "B.CrtYd" user "B.Courtyard")
    (47 "F.CrtYd" user "F.Courtyard")
    (48 "B.Fab" user)
    (49 "F.Fab" user)
  )
	(footprint "kria-k26-devboard-footprints:R_0603_1608Metric" (layer "F.Cu")
    (at 191.2 138.4 -90)
    (descr "Resistor SMD 0603")
    (tags "resistor SMD 0603")
    (property "Author" "Antmicro")
    (property "License" "Apache-2.0")
    (property "MPN" "PMR03EZPJ000")
    (property "Manufacturer" "ROHM Semiconductor")
    (property "Max. Curr." "22.4A")
    (property "Sheetfile" "dc-dc-conventers.kicad_sch")
    (property "Sheetname" "DC/DC conventers")
    (property "Val" "0R")
    (property "ki_description" "Metal strip 0Ohm jumper 22.4A")
    (property "ki_keywords" "Metal strip 0Ohm jumper 22.4A high power hpwr current")
    (attr smd)
    (fp_text reference "R159" (at 6.82 -0.35 -90) (layer "F.SilkS")
        (effects (font (size 0.7 0.7) (thickness 0.15)) (justify left bottom))
    )
    (fp_text value "R_0R_22.4A_0603" (at 0 1.6 -90) (layer "F.Fab") hide
        (effects (font (size 0.7 0.7) (thickness 0.15)) (justify left bottom))
    )
    (fp_text user "License: Apache-2.0" (at -1.25 5.9 -90) (layer "F.Fab") hide
        (effects (font (size 0.7 0.7) (thickness 0.15)) (justify left bottom))
    )
    (fp_text user "${REFERENCE}" (at -1.25 3.898 -90) (layer "F.Fab") hide
        (effects (font (size 0.7 0.7) (thickness 0.15)) (justify left bottom))
    )
    (fp_text user "Author: Antmicro" (at -1.25 4.9 -90) (layer "F.Fab") hide
        (effects (font (size 0.7 0.7) (thickness 0.15)) (justify left bottom))
    )
    (fp_line (start -0.3 -0.3) (end 0.3 -0.3)
      (stroke (width 0.15) (type solid)) (layer "F.SilkS"))
    (fp_line (start -0.3 0.3) (end 0.3 0.3)
      (stroke (width 0.15) (type solid)) (layer "F.SilkS"))
    (fp_rect (start -1.25 -0.7) (end 1.25 0.7)
      (stroke (width 0.05) (type solid)) (fill none) (layer "F.CrtYd"))
    (fp_rect (start -0.8 -0.4) (end 0.8 0.4)
      (stroke (width 0.15) (type solid)) (fill none) (layer "F.Fab"))
    (pad "1" smd roundrect (at -0.7 0 270) (size 0.6 0.8) (layers "F.Cu" "F.Paste" "F.Mask") (roundrect_rratio 0.2)
      (net 771 "/Power Supply/DC/DC conventers/PL_1V2_OUT") (pintype "passive"))
    (pad "2" smd roundrect (at 0.7 0 270) (size 0.6 0.8) (layers "F.Cu" "F.Paste" "F.Mask") (roundrect_rratio 0.2)
      (net 21 "PL_1V2") (pintype "passive"))
  )
	(footprint "kria-k26-devboard-footprints:R_0402_1005Metric" (layer "F.Cu")
    (at 111.945 91.22 180)
    (descr "Resistor SMD 0402")
    (tags "resistor SMD 0402")
    (property "Author" "Antmicro")
    (property "License" "Apache-2.0")
    (property "MPN" "CR0402-FX-2003GLF")
    (property "Manufacturer" "Bourns")
    (property "Sheetfile" "usb.kicad_sch")
    (property "Sheetname" "USB")
    (property "Tolerance" "1%")
    (property "Val" "200k")
    (property "ki_description" "200k resistor in 0402 package with 1% tolerance")
    (attr smd)
    (fp_text reference "R172" (at 3.705 -0.35 180) (layer "F.SilkS")
        (effects (font (size 0.7 0.7) (thickness 0.15)) (justify left bottom))
    )
    (fp_text value "R_200k_0402" (at 0 1.4 180) (layer "F.Fab") hide
        (effects (font (size 0.7 0.7) (thickness 0.15)) (justify left bottom))
    )
    (fp_text user "License: Apache-2.0" (at -0.95 5.169 180) (layer "F.Fab") hide
        (effects (font (size 0.7 0.7) (thickness 0.15)) (justify left bottom))
    )
    (fp_text user "${REFERENCE}" (at -0.95 3.168 180) (layer "F.Fab") hide
        (effects (font (size 0.7 0.7) (thickness 0.15)) (justify left bottom))
    )
    (fp_text user "Author: Antmicro" (at -0.95 4.169 180) (layer "F.Fab") hide
        (effects (font (size 0.7 0.7) (thickness 0.15)) (justify left bottom))
    )
    (fp_rect (start -0.93 -0.47) (end 0.93 0.47)
      (stroke (width 0.05) (type solid)) (fill none) (layer "F.CrtYd"))
    (fp_rect (start -0.5 -0.25) (end 0.5 0.25)
      (stroke (width 0.15) (type solid)) (fill none) (layer "F.Fab"))
    (pad "1" smd roundrect (at -0.485 0 180) (size 0.59 0.64) (layers "F.Cu" "F.Paste" "F.Mask") (roundrect_rratio 0.25)
      (net 666 "Net-(U17-PF26)") (pintype "passive"))
    (pad "2" smd roundrect (at 0.485 0 180) (size 0.59 0.64) (layers "F.Cu" "F.Paste" "F.Mask") (roundrect_rratio 0.25)
      (net 1 "GND") (pintype "passive"))
  )
	(footprint "kria-k26-devboard-footprints:WSON-6-1EP_2x2mm_P0.65mm" (layer "F.Cu")
    (at 151.9 107.9 90)
    (property "Author" "Antmicro")
    (property "License" "Apache-2.0")
    (property "MPN" "NCP730BMT330TBG")
    (property "Manufacturer" "ON Semiconductor")
    (property "Sheetfile" "debug.kicad_sch")
    (property "Sheetname" "Debug and JTAG")
    (property "ki_description" "Linear Voltage Regulator IC Positive Fixed 1 Output 150mA 6-WDFN (2x2)")
    (property "ki_keywords" "SMT, PMIC, IC, LDO, VOLTAGE, REGULATOR")
    (attr smd)
    (fp_text reference "U61" (at 1.56 -1.11 180) (layer "F.SilkS")
        (effects (font (size 0.7 0.7) (thickness 0.15)) (justify left bottom))
    )
    (fp_text value "NCP730BMT330_WSON" (at 0 2.2 90) (layer "F.Fab") hide
        (effects (font (size 0.7 0.7) (thickness 0.15)) (justify left bottom))
    )
    (fp_text user "License: Apache-2.0" (at -1.01 6.4 90) (layer "F.Fab") hide
        (effects (font (size 0.7 0.7) (thickness 0.15)) (justify left bottom))
    )
    (fp_text user "${REFERENCE}" (at -1.01 3.999 90) (layer "F.Fab") hide
        (effects (font (size 0.7 0.7) (thickness 0.15)) (justify left bottom))
    )
    (fp_text user "Author: Antmicro" (at -1.01 5.2 90) (layer "F.Fab") hide
        (effects (font (size 0.7 0.7) (thickness 0.15)) (justify left bottom))
    )
    (fp_line (start -1 1) (end 1 1)
      (stroke (width 0.12) (type solid)) (layer "F.SilkS"))
    (fp_line (start 1 -1) (end -1.05 -1)
      (stroke (width 0.12) (type solid)) (layer "F.SilkS"))
    (fp_circle (center -1.275 -1.075) (end -1.224 -1.075)
      (stroke (width 0.15) (type solid)) (fill solid) (layer "F.SilkS"))
    (fp_rect (start -1.45 -1.25) (end 1.45 1.25)
      (stroke (width 0.05) (type solid)) (fill none) (layer "F.CrtYd"))
    (pad "1" smd roundrect (at -0.975 -0.652 90) (size 0.45 0.4) (layers "F.Cu" "F.Paste" "F.Mask") (roundrect_rratio 0.25)
      (net 187 "/Debug and JTAG/PD_3V3") (pinfunction "V_{OUT}") (pintype "power_out"))
    (pad "2" smd roundrect (at -0.975 0 90) (size 0.45 0.4) (layers "F.Cu" "F.Paste" "F.Mask") (roundrect_rratio 0.25)
      (net 794 "unconnected-(U61-NC-Pad2)") (pinfunction "NC") (pintype "no_connect"))
    (pad "3" smd roundrect (at -0.975 0.65 90) (size 0.45 0.4) (layers "F.Cu" "F.Paste" "F.Mask") (roundrect_rratio 0.25)
      (net 1 "GND") (pinfunction "GND") (pintype "power_in"))
    (pad "4" smd roundrect (at 0.973 0.65 90) (size 0.45 0.4) (layers "F.Cu" "F.Paste" "F.Mask") (roundrect_rratio 0.25)
      (net 313 "/Debug and JTAG/USB_VBUS") (pinfunction "EN") (pintype "input"))
    (pad "5" smd roundrect (at 0.973 0 90) (size 0.45 0.4) (layers "F.Cu" "F.Paste" "F.Mask") (roundrect_rratio 0.25)
      (net 795 "unconnected-(U61-PG-Pad5)") (pinfunction "PG") (pintype "open_collector+no_connect"))
    (pad "6" smd roundrect (at 0.973 -0.652 90) (size 0.45 0.4) (layers "F.Cu" "F.Paste" "F.Mask") (roundrect_rratio 0.25)
      (net 313 "/Debug and JTAG/USB_VBUS") (pinfunction "V_{IN}") (pintype "power_in"))
    (pad "7" smd roundrect (at 0 0 90) (size 1.12 1.72) (layers "F.Cu" "F.Paste" "F.Mask") (roundrect_rratio 0.1)
      (net 1 "GND") (pinfunction "GND") (pintype "passive"))
  )
	(footprint "kria-k26-devboard-footprints:R_0603_1608Metric" (layer "F.Cu")
    (at 164.625 128.2 90)
    (descr "Resistor SMD 0603")
    (tags "resistor SMD 0603")
    (property "Author" "Antmicro")
    (property "License" "Apache-2.0")
    (property "MPN" "PMR03EZPJ000")
    (property "Manufacturer" "ROHM Semiconductor")
    (property "Max. Curr." "22.4A")
    (property "Sheetfile" "dc-dc-conventers.kicad_sch")
    (property "Sheetname" "DC/DC conventers")
    (property "Val" "0R")
    (property "ki_description" "Metal strip 0Ohm jumper 22.4A")
    (property "ki_keywords" "Metal strip 0Ohm jumper 22.4A high power hpwr current")
    (attr smd)
    (fp_text reference "R161" (at -3.73 -0.295 90) (layer "F.SilkS")
        (effects (font (size 0.7 0.7) (thickness 0.15)) (justify left bottom))
    )
    (fp_text value "R_0R_22.4A_0603" (at 0 1.6 90) (layer "F.Fab") hide
        (effects (font (size 0.7 0.7) (thickness 0.15)) (justify left bottom))
    )
    (fp_text user "${REFERENCE}" (at -1.25 3.898 90) (layer "F.Fab") hide
        (effects (font (size 0.7 0.7) (thickness 0.15)) (justify left bottom))
    )
    (fp_text user "License: Apache-2.0" (at -1.25 5.9 90) (layer "F.Fab") hide
        (effects (font (size 0.7 0.7) (thickness 0.15)) (justify left bottom))
    )
    (fp_text user "Author: Antmicro" (at -1.25 4.9 90) (layer "F.Fab") hide
        (effects (font (size 0.7 0.7) (thickness 0.15)) (justify left bottom))
    )
    (fp_line (start -0.3 -0.3) (end 0.3 -0.3)
      (stroke (width 0.15) (type solid)) (layer "F.SilkS"))
    (fp_line (start -0.3 0.3) (end 0.3 0.3)
      (stroke (width 0.15) (type solid)) (layer "F.SilkS"))
    (fp_rect (start -1.25 -0.7) (end 1.25 0.7)
      (stroke (width 0.05) (type solid)) (fill none) (layer "F.CrtYd"))
    (fp_rect (start -0.8 -0.4) (end 0.8 0.4)
      (stroke (width 0.15) (type solid)) (fill none) (layer "F.Fab"))
    (pad "1" smd roundrect (at -0.7 0 90) (size 0.6 0.8) (layers "F.Cu" "F.Paste" "F.Mask") (roundrect_rratio 0.2)
      (net 773 "/Power Supply/DC/DC conventers/SOM_5V_OUT") (pintype "passive"))
    (pad "2" smd roundrect (at 0.7 0 90) (size 0.6 0.8) (layers "F.Cu" "F.Paste" "F.Mask") (roundrect_rratio 0.2)
      (net 8 "SOM_5V0") (pintype "passive"))
  )
	(footprint "kria-k26-devboard-footprints:R_0402_1005Metric" (layer "F.Cu")
    (at 146.05 142.425 90)
    (descr "Resistor SMD 0402")
    (tags "resistor SMD 0402")
    (property "Author" "Antmicro")
    (property "License" "Apache-2.0")
    (property "MPN" "CR0402-FX-5111GLF")
    (property "Manufacturer" "Bourns")
    (property "Sheetfile" "debug.kicad_sch")
    (property "Sheetname" "Debug and JTAG")
    (property "Tolerance" "1%")
    (property "Val" "5k11")
    (property "ki_description" "5k11 resistor in 0402 package with 1% tolerance")
    (attr smd)
    (fp_text reference "R167" (at 0.945 0.37 90) (layer "F.SilkS")
        (effects (font (size 0.7 0.7) (thickness 0.15)) (justify left bottom))
    )
    (fp_text value "R_5k11_0402" (at 0 1.4 90) (layer "F.Fab") hide
        (effects (font (size 0.7 0.7) (thickness 0.15)) (justify left bottom))
    )
    (fp_text user "License: Apache-2.0" (at -0.95 5.169 90) (layer "F.Fab") hide
        (effects (font (size 0.7 0.7) (thickness 0.15)) (justify left bottom))
    )
    (fp_text user "Author: Antmicro" (at -0.95 4.169 90) (layer "F.Fab") hide
        (effects (font (size 0.7 0.7) (thickness 0.15)) (justify left bottom))
    )
    (fp_text user "${REFERENCE}" (at -0.95 3.168 90) (layer "F.Fab") hide
        (effects (font (size 0.7 0.7) (thickness 0.15)) (justify left bottom))
    )
    (fp_rect (start -0.93 -0.47) (end 0.93 0.47)
      (stroke (width 0.05) (type solid)) (fill none) (layer "F.CrtYd"))
    (fp_rect (start -0.5 -0.25) (end 0.5 0.25)
      (stroke (width 0.15) (type solid)) (fill none) (layer "F.Fab"))
    (pad "1" smd roundrect (at -0.485 0 90) (size 0.59 0.64) (layers "F.Cu" "F.Paste" "F.Mask") (roundrect_rratio 0.25)
      (net 358 "Net-(J8-CC_{2})") (pintype "passive"))
    (pad "2" smd roundrect (at 0.485 0 90) (size 0.59 0.64) (layers "F.Cu" "F.Paste" "F.Mask") (roundrect_rratio 0.25)
      (net 1 "GND") (pintype "passive"))
  )
	(footprint "kria-k26-devboard-footprints:TP_SMD_0.75mm" (layer "F.Cu")
    (at 81.55 106.95 180)
    (property "Author" "Antmicro")
    (property "License" "Apache-2.0")
    (property "MPN" "")
    (property "Manufacturer" "")
    (property "Sheetfile" "k26_som.kicad_sch")
    (property "Sheetname" "Xilinx K26 SOM")
    (property "ki_description" "Test Point 0.75mm")
    (attr exclude_from_pos_files)
    (fp_text reference "TP57" (at 3.36 -0.2808 180) (layer "F.SilkS")
        (effects (font (size 0.7 0.7) (thickness 0.15)) (justify left bottom))
    )
    (fp_text value "TP_0.75mm_SMD" (at 0 1.2 180) (layer "F.Fab") hide
        (effects (font (size 0.7 0.7) (thickness 0.15)) (justify left bottom))
    )
    (fp_text user "License: Apache-2.0" (at -0.4 5.101 180) (layer "F.Fab") hide
        (effects (font (size 0.7 0.7) (thickness 0.15)) (justify left bottom))
    )
    (fp_text user "${REFERENCE}" (at -0.4 2.7 180) (layer "F.Fab") hide
        (effects (font (size 0.7 0.7) (thickness 0.15)) (justify left bottom))
    )
    (fp_text user "Author: Antmicro" (at -0.4 3.901 180) (layer "F.Fab") hide
        (effects (font (size 0.7 0.7) (thickness 0.15)) (justify left bottom))
    )
    (pad "1" smd circle (at 0 0 180) (size 0.75 0.75) (layers "F.Cu" "F.Mask")
      (net 475 "/Xilinx K26 SOM/PWR_GD_PL_M2C") (pinfunction "1") (pintype "passive"))
  )
	(footprint "kria-k26-devboard-footprints:TP_SMD_0.75mm" (layer "F.Cu")
    (at 155.7492 150.8 -90)
    (property "Author" "Antmicro")
    (property "License" "Apache-2.0")
    (property "MPN" "")
    (property "Manufacturer" "")
    (property "Sheetfile" "debug.kicad_sch")
    (property "Sheetname" "Debug and JTAG")
    (property "ki_description" "Test Point 0.75mm")
    (attr exclude_from_pos_files)
    (fp_text reference "TP65" (at -0.47 -0.4308 -90) (layer "F.SilkS")
        (effects (font (size 0.7 0.7) (thickness 0.15)) (justify left bottom))
    )
    (fp_text value "TP_0.75mm_SMD" (at 0 1.2 -90) (layer "F.Fab") hide
        (effects (font (size 0.7 0.7) (thickness 0.15)) (justify left bottom))
    )
    (fp_text user "${REFERENCE}" (at -0.4 2.7 -90) (layer "F.Fab") hide
        (effects (font (size 0.7 0.7) (thickness 0.15)) (justify left bottom))
    )
    (fp_text user "License: Apache-2.0" (at -0.4 5.101 -90) (layer "F.Fab") hide
        (effects (font (size 0.7 0.7) (thickness 0.15)) (justify left bottom))
    )
    (fp_text user "Author: Antmicro" (at -0.4 3.901 -90) (layer "F.Fab") hide
        (effects (font (size 0.7 0.7) (thickness 0.15)) (justify left bottom))
    )
    (pad "1" smd circle (at 0 0 270) (size 0.75 0.75) (layers "F.Cu" "F.Mask")
      (net 1 "GND") (pinfunction "1") (pintype "passive"))
  )
	(footprint "kria-k26-devboard-footprints:R_0603_1608Metric" (layer "F.Cu")
    (at 181.5 137.9)
    (descr "Resistor SMD 0603")
    (tags "resistor SMD 0603")
    (property "Author" "Antmicro")
    (property "License" "Apache-2.0")
    (property "MPN" "PMR03EZPJ000")
    (property "Manufacturer" "ROHM Semiconductor")
    (property "Max. Curr." "22.4A")
    (property "Sheetfile" "dc-dc-conventers.kicad_sch")
    (property "Sheetname" "DC/DC conventers")
    (property "Val" "0R")
    (property "ki_description" "Metal strip 0Ohm jumper 22.4A")
    (property "ki_keywords" "Metal strip 0Ohm jumper 22.4A high power hpwr current")
    (attr smd)
    (fp_text reference "R158" (at -1.09 2.98 90) (layer "F.SilkS")
        (effects (font (size 0.7 0.7) (thickness 0.15)) (justify left bottom))
    )
    (fp_text value "R_0R_22.4A_0603" (at 0 1.6) (layer "F.Fab") hide
        (effects (font (size 0.7 0.7) (thickness 0.15)) (justify left bottom))
    )
    (fp_text user "${REFERENCE}" (at -1.25 3.898) (layer "F.Fab") hide
        (effects (font (size 0.7 0.7) (thickness 0.15)) (justify left bottom))
    )
    (fp_text user "License: Apache-2.0" (at -1.25 5.9) (layer "F.Fab") hide
        (effects (font (size 0.7 0.7) (thickness 0.15)) (justify left bottom))
    )
    (fp_text user "Author: Antmicro" (at -1.25 4.9) (layer "F.Fab") hide
        (effects (font (size 0.7 0.7) (thickness 0.15)) (justify left bottom))
    )
    (fp_line (start -0.3 -0.3) (end 0.3 -0.3)
      (stroke (width 0.15) (type solid)) (layer "F.SilkS"))
    (fp_line (start -0.3 0.3) (end 0.3 0.3)
      (stroke (width 0.15) (type solid)) (layer "F.SilkS"))
    (fp_rect (start -1.25 -0.7) (end 1.25 0.7)
      (stroke (width 0.05) (type solid)) (fill none) (layer "F.CrtYd"))
    (fp_rect (start -0.8 -0.4) (end 0.8 0.4)
      (stroke (width 0.15) (type solid)) (fill none) (layer "F.Fab"))
    (pad "1" smd roundrect (at -0.7 0) (size 0.6 0.8) (layers "F.Cu" "F.Paste" "F.Mask") (roundrect_rratio 0.2)
      (net 770 "/Power Supply/DC/DC conventers/PL_3V3_OUT") (pintype "passive"))
    (pad "2" smd roundrect (at 0.7 0) (size 0.6 0.8) (layers "F.Cu" "F.Paste" "F.Mask") (roundrect_rratio 0.2)
      (net 20 "PL_3V3") (pintype "passive"))
  )
	(footprint "kria-k26-devboard-footprints:R_0402_1005Metric" (layer "F.Cu")
    (at 139.75 138)
    (descr "Resistor SMD 0402")
    (tags "resistor SMD 0402")
    (property "Author" "Antmicro")
    (property "License" "Apache-2.0")
    (property "MPN" "CR0402-FX-1002GLF")
    (property "Manufacturer" "Bourns")
    (property "Sheetfile" "sd-3-card.kicad_sch")
    (property "Sheetname" "SD 3.0 card")
    (property "Tolerance" "1%")
    (property "Val" "10k")
    (property "ki_description" "10k resistor in 0402 package with 1% tolerance")
    (attr smd)
    (fp_text reference "R168" (at -0.09 1.18) (layer "F.SilkS")
        (effects (font (size 0.7 0.7) (thickness 0.15)) (justify left bottom))
    )
    (fp_text value "R_10k_0402" (at 0 1.4) (layer "F.Fab") hide
        (effects (font (size 0.7 0.7) (thickness 0.15)) (justify left bottom))
    )
    (fp_text user "License: Apache-2.0" (at -0.95 5.169) (layer "F.Fab") hide
        (effects (font (size 0.7 0.7) (thickness 0.15)) (justify left bottom))
    )
    (fp_text user "${REFERENCE}" (at -0.95 3.168) (layer "F.Fab") hide
        (effects (font (size 0.7 0.7) (thickness 0.15)) (justify left bottom))
    )
    (fp_text user "Author: Antmicro" (at -0.95 4.169) (layer "F.Fab") hide
        (effects (font (size 0.7 0.7) (thickness 0.15)) (justify left bottom))
    )
    (fp_rect (start -0.93 -0.47) (end 0.93 0.47)
      (stroke (width 0.05) (type solid)) (fill none) (layer "F.CrtYd"))
    (fp_rect (start -0.5 -0.25) (end 0.5 0.25)
      (stroke (width 0.15) (type solid)) (fill none) (layer "F.Fab"))
    (pad "1" smd roundrect (at -0.485 0) (size 0.59 0.64) (layers "F.Cu" "F.Paste" "F.Mask") (roundrect_rratio 0.25)
      (net 695 "Net-(U6-ST)") (pintype "passive"))
    (pad "2" smd roundrect (at 0.485 0) (size 0.59 0.64) (layers "F.Cu" "F.Paste" "F.Mask") (roundrect_rratio 0.25)
      (net 17 "PS_1V8") (pintype "passive"))
  )
	(footprint "kria-k26-devboard-footprints:R_0402_1005Metric" (layer "F.Cu")
    (at 174.82 127.73 90)
    (descr "Resistor SMD 0402")
    (tags "resistor SMD 0402")
    (property "Author" "Antmicro")
    (property "License" "Apache-2.0")
    (property "MPN" "CR0402-FX-1473GLF")
    (property "Manufacturer" "Bourns")
    (property "Sheetfile" "dc-dc-conventers.kicad_sch")
    (property "Sheetname" "DC/DC conventers")
    (property "Tolerance" "1%")
    (property "Val" "147k")
    (property "ki_description" "147k resistor in 0402 package with 1% tolerance")
    (attr smd)
    (fp_text reference "R124" (at -1.37 -2.6 90) (layer "F.SilkS")
        (effects (font (size 0.7 0.7) (thickness 0.15)) (justify left bottom))
    )
    (fp_text value "R_147k_0402" (at 0 1.4 90) (layer "F.Fab") hide
        (effects (font (size 0.7 0.7) (thickness 0.15)) (justify left bottom))
    )
    (fp_text user "Author: Antmicro" (at -0.95 4.169 90) (layer "F.Fab") hide
        (effects (font (size 0.7 0.7) (thickness 0.15)) (justify left bottom))
    )
    (fp_text user "License: Apache-2.0" (at -0.95 5.169 90) (layer "F.Fab") hide
        (effects (font (size 0.7 0.7) (thickness 0.15)) (justify left bottom))
    )
    (fp_text user "${REFERENCE}" (at -0.95 3.168 90) (layer "F.Fab") hide
        (effects (font (size 0.7 0.7) (thickness 0.15)) (justify left bottom))
    )
    (fp_rect (start -0.93 -0.47) (end 0.93 0.47)
      (stroke (width 0.05) (type solid)) (fill none) (layer "F.CrtYd"))
    (fp_rect (start -0.5 -0.25) (end 0.5 0.25)
      (stroke (width 0.15) (type solid)) (fill none) (layer "F.Fab"))
    (pad "1" smd roundrect (at -0.485 0 90) (size 0.59 0.64) (layers "F.Cu" "F.Paste" "F.Mask") (roundrect_rratio 0.25)
      (net 774 "/Power Supply/DC/DC conventers/SOM_5V_FB") (pintype "passive"))
    (pad "2" smd roundrect (at 0.485 0 90) (size 0.59 0.64) (layers "F.Cu" "F.Paste" "F.Mask") (roundrect_rratio 0.25)
      (net 255 "Net-(U48-FB)") (pintype "passive"))
  )
)
